(kicad_pcb
	(version 20260206)
	(generator "pcbnew")
	(generator_version "10.0")
	(general
		(thickness 1.6)
		(legacy_teardrops no)
	)
	(paper "A4")
	(title_block
		(title "03242023_DA0F0TMBIJ0_F0T_Motherboard_J_brd_V01_OCP.brd")
		(comment 1 "Grand Teton / footprints 2714-2719 of 6105")
	)
	(layers
		(0 "F.Cu" signal "TOP")
		(4 "In1.Cu" signal "GND")
		(6 "In2.Cu" signal "IN1")
		(8 "In3.Cu" signal "GND1")
		(10 "In4.Cu" signal "IN2")
		(12 "In5.Cu" signal "GND2")
		(14 "In6.Cu" signal "IN3")
		(16 "In7.Cu" signal "GND3")
		(18 "In8.Cu" signal "VCC")
		(20 "In9.Cu" signal "VCC1")
		(22 "In10.Cu" signal "GND4")
		(24 "In11.Cu" signal "IN4")
		(26 "In12.Cu" signal "GND5")
		(28 "In13.Cu" signal "IN5")
		(30 "In14.Cu" signal "GND6")
		(32 "In15.Cu" signal "IN6")
		(34 "In16.Cu" signal "GND7")
		(2 "B.Cu" signal "BOTTOM")
		(9 "F.Adhes" user "F.Adhesive")
		(11 "B.Adhes" user "B.Adhesive")
		(13 "F.Paste" user "Package Geometry/Pastemask Top")
		(15 "B.Paste" user "Package Geometry/Pastemask Bottom")
		(5 "F.SilkS" user "Ref Des/Silkscreen Top")
		(7 "B.SilkS" user "Ref Des/Silkscreen Bottom")
		(1 "F.Mask" user "Board Geometry/Soldermask Top")
		(3 "B.Mask" user "Board Geometry/Soldermask Bottom")
		(17 "Dwgs.User" user "User.Drawings")
		(19 "Cmts.User" user "User.Comments")
		(21 "Eco1.User" user "User.Eco1")
		(23 "Eco2.User" user "User.Eco2")
		(25 "Edge.Cuts" user "Board Geometry/Outline")
		(27 "Margin" user)
		(31 "F.CrtYd" user "Package Geometry/Place Bound Top")
		(29 "B.CrtYd" user "Package Geometry/Place Bound Bottom")
		(35 "F.Fab" user "Ref Des/Assembly Top")
		(33 "B.Fab" user "Ref Des/Assembly Bottom")
	)
	(footprint ""
		(layer "F.Cu")
		(at 30.748732 -403.695408 180)
		(property "Reference" "R3320"
			(at 0 0 180)
			(layer "F.SilkS")
			(hide yes)
			(effects
				(font
					(size 1.27 1.27)
				)
			)
		)
		(property "Value" ""
			(at 0 0 180)
			(layer "F.Fab")
			(effects
				(font
					(size 1.27 1.27)
				)
			)
		)
		(duplicate_pad_numbers_are_jumpers no)
		(fp_line
			(start 0.7874 0.4064)
			(end -0.7874 0.4064)
			(stroke
				(width 0.1524)
				(type default)
			)
			(layer "F.SilkS")
		)
		(fp_line
			(start 0.7874 -0.4064)
			(end 0.7874 0.4064)
			(stroke
				(width 0.1524)
				(type default)
			)
			(layer "F.SilkS")
		)
		(fp_line
			(start -0.7874 0.4064)
			(end -0.7874 -0.4064)
			(stroke
				(width 0.1524)
				(type default)
			)
			(layer "F.SilkS")
		)
		(fp_line
			(start -0.7874 -0.4064)
			(end 0.7874 -0.4064)
			(stroke
				(width 0.1524)
				(type default)
			)
			(layer "F.SilkS")
		)
		(fp_line
			(start 0.67945 0.3048)
			(end 0.120396 0.3048)
			(stroke
				(width 0.1)
				(type default)
			)
			(layer "F.Fab")
		)
		(fp_line
			(start 0.67945 -0.3048)
			(end 0.67945 0.3048)
			(stroke
				(width 0.1)
				(type default)
			)
			(layer "F.Fab")
		)
		(fp_line
			(start 0.12065 -0.2794)
			(end 0.12065 -0.3048)
			(stroke
				(width 0.1)
				(type default)
			)
			(layer "F.Fab")
		)
		(fp_line
			(start 0.12065 -0.3048)
			(end 0.67945 -0.3048)
			(stroke
				(width 0.1)
				(type default)
			)
			(layer "F.Fab")
		)
		(fp_line
			(start 0.120396 0.3048)
			(end 0.120396 0.2794)
			(stroke
				(width 0.1)
				(type default)
			)
			(layer "F.Fab")
		)
		(fp_line
			(start 0.120396 0.2794)
			(end -0.12065 0.2794)
			(stroke
				(width 0.1)
				(type default)
			)
			(layer "F.Fab")
		)
		(fp_line
			(start -0.12065 0.3048)
			(end -0.67945 0.3048)
			(stroke
				(width 0.1)
				(type default)
			)
			(layer "F.Fab")
		)
		(fp_line
			(start -0.12065 0.2794)
			(end -0.12065 0.3048)
			(stroke
				(width 0.1)
				(type default)
			)
			(layer "F.Fab")
		)
		(fp_line
			(start -0.12065 -0.2794)
			(end 0.12065 -0.2794)
			(stroke
				(width 0.1)
				(type default)
			)
			(layer "F.Fab")
		)
		(fp_line
			(start -0.12065 -0.305054)
			(end -0.12065 -0.2794)
			(stroke
				(width 0.1)
				(type default)
			)
			(layer "F.Fab")
		)
		(fp_line
			(start -0.67945 0.3048)
			(end -0.67945 -0.305054)
			(stroke
				(width 0.1)
				(type default)
			)
			(layer "F.Fab")
		)
		(fp_line
			(start -0.67945 -0.305054)
			(end -0.12065 -0.305054)
			(stroke
				(width 0.1)
				(type default)
			)
			(layer "F.Fab")
		)
		(pad "1" smd circle
			(at -0.40005 0 180)
			(size 0 0)
			(layers "F.Cu" "F.Mask" "F.Paste")
			(net "P3V3_AUX")
		)
		(pad "2" smd circle
			(at 0.40005 0 180)
			(size 0 0)
			(layers "F.Cu" "F.Mask" "F.Paste")
			(net "GPU_FPGA_READY_N")
		)
	)
	(footprint ""
		(layer "F.Cu")
		(at 179.352448 -405.303482 180)
		(property "Reference" "PC2192"
			(at 0 0 180)
			(layer "F.SilkS")
			(hide yes)
			(effects
				(font
					(size 1.27 1.27)
				)
			)
		)
		(property "Value" ""
			(at 0 0 180)
			(layer "F.Fab")
			(effects
				(font
					(size 1.27 1.27)
				)
			)
		)
		(duplicate_pad_numbers_are_jumpers no)
		(fp_line
			(start 0.7874 0.4064)
			(end -0.7874 0.4064)
			(stroke
				(width 0.1524)
				(type default)
			)
			(layer "F.SilkS")
		)
		(fp_line
			(start 0.7874 -0.4064)
			(end 0.7874 0.4064)
			(stroke
				(width 0.1524)
				(type default)
			)
			(layer "F.SilkS")
		)
		(fp_line
			(start -0.7874 0.4064)
			(end -0.7874 -0.4064)
			(stroke
				(width 0.1524)
				(type default)
			)
			(layer "F.SilkS")
		)
		(fp_line
			(start -0.7874 -0.4064)
			(end 0.7874 -0.4064)
			(stroke
				(width 0.1524)
				(type default)
			)
			(layer "F.SilkS")
		)
		(fp_line
			(start 0.67945 0.3048)
			(end 0.120396 0.3048)
			(stroke
				(width 0.1)
				(type default)
			)
			(layer "F.Fab")
		)
		(fp_line
			(start 0.67945 -0.3048)
			(end 0.67945 0.3048)
			(stroke
				(width 0.1)
				(type default)
			)
			(layer "F.Fab")
		)
		(fp_line
			(start 0.12065 -0.2794)
			(end 0.12065 -0.3048)
			(stroke
				(width 0.1)
				(type default)
			)
			(layer "F.Fab")
		)
		(fp_line
			(start 0.12065 -0.3048)
			(end 0.67945 -0.3048)
			(stroke
				(width 0.1)
				(type default)
			)
			(layer "F.Fab")
		)
		(fp_line
			(start 0.120396 0.3048)
			(end 0.120396 0.2794)
			(stroke
				(width 0.1)
				(type default)
			)
			(layer "F.Fab")
		)
		(fp_line
			(start 0.120396 0.2794)
			(end -0.12065 0.2794)
			(stroke
				(width 0.1)
				(type default)
			)
			(layer "F.Fab")
		)
		(fp_line
			(start -0.12065 0.3048)
			(end -0.67945 0.3048)
			(stroke
				(width 0.1)
				(type default)
			)
			(layer "F.Fab")
		)
		(fp_line
			(start -0.12065 0.2794)
			(end -0.12065 0.3048)
			(stroke
				(width 0.1)
				(type default)
			)
			(layer "F.Fab")
		)
		(fp_line
			(start -0.12065 -0.2794)
			(end 0.12065 -0.2794)
			(stroke
				(width 0.1)
				(type default)
			)
			(layer "F.Fab")
		)
		(fp_line
			(start -0.12065 -0.305054)
			(end -0.12065 -0.2794)
			(stroke
				(width 0.1)
				(type default)
			)
			(layer "F.Fab")
		)
		(fp_line
			(start -0.67945 0.3048)
			(end -0.67945 -0.305054)
			(stroke
				(width 0.1)
				(type default)
			)
			(layer "F.Fab")
		)
		(fp_line
			(start -0.67945 -0.305054)
			(end -0.12065 -0.305054)
			(stroke
				(width 0.1)
				(type default)
			)
			(layer "F.Fab")
		)
		(pad "1" smd circle
			(at -0.40005 0 180)
			(size 0 0)
			(layers "F.Cu" "F.Mask" "F.Paste")
			(net "HSC_VTEMP")
		)
		(pad "2" smd circle
			(at 0.40005 0 180)
			(size 0 0)
			(layers "F.Cu" "F.Mask" "F.Paste")
			(net "AGND_HSC")
		)
	)
	(footprint ""
		(layer "F.Cu")
		(at 300.54042 -424.00601 90)
		(property "Reference" "Q132"
			(at -7.76986 7.383272 90)
			(unlocked yes)
			(layer "F.SilkS")
			(effects
				(font
					(size 0.7874 0.5842)
					(thickness 0.1524)
				)
				(justify left)
			)
		)
		(property "Value" ""
			(at 0 0 90)
			(layer "F.Fab")
			(effects
				(font
					(size 1.27 1.27)
				)
			)
		)
		(duplicate_pad_numbers_are_jumpers no)
		(fp_line
			(start 1.332738 -1.100074)
			(end 1.332738 1.100074)
			(stroke
				(width 0.1524)
				(type default)
			)
			(layer "F.SilkS")
		)
		(fp_line
			(start 0.4826 -1.100074)
			(end 1.332738 -1.100074)
			(stroke
				(width 0.1524)
				(type default)
			)
			(layer "F.SilkS")
		)
		(fp_line
			(start -0.4826 -1.100074)
			(end 0 -0.541274)
			(stroke
				(width 0.1524)
				(type default)
			)
			(layer "F.SilkS")
		)
		(fp_line
			(start -1.332738 -1.100074)
			(end -0.4826 -1.100074)
			(stroke
				(width 0.1524)
				(type default)
			)
			(layer "F.SilkS")
		)
		(fp_line
			(start 0 -0.541274)
			(end 0.4826 -1.100074)
			(stroke
				(width 0.1524)
				(type default)
			)
			(layer "F.SilkS")
		)
		(fp_line
			(start 1.332738 1.100074)
			(end -1.332738 1.100074)
			(stroke
				(width 0.1524)
				(type default)
			)
			(layer "F.SilkS")
		)
		(fp_line
			(start -1.332738 1.100074)
			(end -1.332738 -1.100074)
			(stroke
				(width 0.1524)
				(type default)
			)
			(layer "F.SilkS")
		)
		(fp_poly
			(pts
				(xy -2.37998 -1.432814) (xy -1.677924 -1.081786) (xy -2.37998 -0.730758)
			)
			(stroke
				(width 0)
				(type default)
			)
			(fill yes)
			(layer "F.SilkS")
		)
		(fp_line
			(start 0.674878 -1.100074)
			(end 0.674878 1.100074)
			(stroke
				(width 0.1)
				(type default)
			)
			(layer "F.Fab")
		)
		(fp_line
			(start -0.674878 -1.100074)
			(end 0.674878 -1.100074)
			(stroke
				(width 0.1)
				(type default)
			)
			(layer "F.Fab")
		)
		(fp_line
			(start 0.674878 1.100074)
			(end -0.674878 1.100074)
			(stroke
				(width 0.1)
				(type default)
			)
			(layer "F.Fab")
		)
		(fp_line
			(start -0.674878 1.100074)
			(end -0.674878 -1.100074)
			(stroke
				(width 0.1)
				(type default)
			)
			(layer "F.Fab")
		)
		(fp_poly
			(pts
				(xy -2.2352 -0.298958) (xy -2.2352 -1.001014) (xy -1.533144 -0.649986)
			)
			(stroke
				(width 0)
				(type default)
			)
			(fill yes)
			(layer "F.Fab")
		)
		(pad "1" smd rect
			(at -0.94996 -0.649986 180)
			(size 0.4318 0.508)
			(layers "F.Cu" "F.Mask" "F.Paste")
			(net "GND")
		)
		(pad "2" smd rect
			(at -0.94996 0 180)
			(size 0.4318 0.508)
			(layers "F.Cu" "F.Mask" "F.Paste")
			(net "PRSNT_CABLE_GPU_B3_N")
		)
		(pad "3" smd rect
			(at -0.94996 0.649986 180)
			(size 0.4318 0.508)
			(layers "F.Cu" "F.Mask" "F.Paste")
			(net "PRSNT_CABLE_GPU_B3_ISO_N")
		)
		(pad "4" smd rect
			(at 0.94996 0.649986 180)
			(size 0.4318 0.508)
			(layers "F.Cu" "F.Mask" "F.Paste")
			(net "GND")
		)
		(pad "5" smd rect
			(at 0.94996 0 180)
			(size 0.4318 0.508)
			(layers "F.Cu" "F.Mask" "F.Paste")
			(net "PRSNT_CABLE_GPU_B3")
		)
		(pad "6" smd rect
			(at 0.94996 -0.649986 180)
			(size 0.4318 0.508)
			(layers "F.Cu" "F.Mask" "F.Paste")
			(net "PRSNT_CABLE_GPU_B3")
		)
	)
	(footprint ""
		(layer "F.Cu")
		(at 56.950102 -336.006186 180)
		(property "Reference" "PR560"
			(at 0 0 180)
			(layer "F.SilkS")
			(hide yes)
			(effects
				(font
					(size 1.27 1.27)
				)
			)
		)
		(property "Value" ""
			(at 0 0 180)
			(layer "F.Fab")
			(effects
				(font
					(size 1.27 1.27)
				)
			)
		)
		(duplicate_pad_numbers_are_jumpers no)
		(fp_line
			(start 0.7874 0.4064)
			(end -0.7874 0.4064)
			(stroke
				(width 0.1524)
				(type default)
			)
			(layer "F.SilkS")
		)
		(fp_line
			(start 0.7874 -0.4064)
			(end 0.7874 0.4064)
			(stroke
				(width 0.1524)
				(type default)
			)
			(layer "F.SilkS")
		)
		(fp_line
			(start -0.7874 0.4064)
			(end -0.7874 -0.4064)
			(stroke
				(width 0.1524)
				(type default)
			)
			(layer "F.SilkS")
		)
		(fp_line
			(start -0.7874 -0.4064)
			(end 0.7874 -0.4064)
			(stroke
				(width 0.1524)
				(type default)
			)
			(layer "F.SilkS")
		)
		(fp_line
			(start 0.67945 0.3048)
			(end 0.120396 0.3048)
			(stroke
				(width 0.1)
				(type default)
			)
			(layer "F.Fab")
		)
		(fp_line
			(start 0.67945 -0.3048)
			(end 0.67945 0.3048)
			(stroke
				(width 0.1)
				(type default)
			)
			(layer "F.Fab")
		)
		(fp_line
			(start 0.12065 -0.2794)
			(end 0.12065 -0.3048)
			(stroke
				(width 0.1)
				(type default)
			)
			(layer "F.Fab")
		)
		(fp_line
			(start 0.12065 -0.3048)
			(end 0.67945 -0.3048)
			(stroke
				(width 0.1)
				(type default)
			)
			(layer "F.Fab")
		)
		(fp_line
			(start 0.120396 0.3048)
			(end 0.120396 0.2794)
			(stroke
				(width 0.1)
				(type default)
			)
			(layer "F.Fab")
		)
		(fp_line
			(start 0.120396 0.2794)
			(end -0.12065 0.2794)
			(stroke
				(width 0.1)
				(type default)
			)
			(layer "F.Fab")
		)
		(fp_line
			(start -0.12065 0.3048)
			(end -0.67945 0.3048)
			(stroke
				(width 0.1)
				(type default)
			)
			(layer "F.Fab")
		)
		(fp_line
			(start -0.12065 0.2794)
			(end -0.12065 0.3048)
			(stroke
				(width 0.1)
				(type default)
			)
			(layer "F.Fab")
		)
		(fp_line
			(start -0.12065 -0.2794)
			(end 0.12065 -0.2794)
			(stroke
				(width 0.1)
				(type default)
			)
			(layer "F.Fab")
		)
		(fp_line
			(start -0.12065 -0.305054)
			(end -0.12065 -0.2794)
			(stroke
				(width 0.1)
				(type default)
			)
			(layer "F.Fab")
		)
		(fp_line
			(start -0.67945 0.3048)
			(end -0.67945 -0.305054)
			(stroke
				(width 0.1)
				(type default)
			)
			(layer "F.Fab")
		)
		(fp_line
			(start -0.67945 -0.305054)
			(end -0.12065 -0.305054)
			(stroke
				(width 0.1)
				(type default)
			)
			(layer "F.Fab")
		)
		(pad "1" smd circle
			(at -0.40005 0 180)
			(size 0 0)
			(layers "F.Cu" "F.Mask" "F.Paste")
			(net "VSENSE_PVCCFA_EHV_FIVRA_CPU1_DN")
		)
		(pad "2" smd circle
			(at 0.40005 0 180)
			(size 0 0)
			(layers "F.Cu" "F.Mask" "F.Paste")
			(net "GND")
		)
	)
	(footprint ""
		(layer "F.Cu")
		(at 209.74558 -130.830828)
		(property "Reference" "R1688"
			(at 0 0 0)
			(layer "F.SilkS")
			(hide yes)
			(effects
				(font
					(size 1.27 1.27)
				)
			)
		)
		(property "Value" ""
			(at 0 0 0)
			(layer "F.Fab")
			(effects
				(font
					(size 1.27 1.27)
				)
			)
		)
		(duplicate_pad_numbers_are_jumpers no)
		(fp_line
			(start -0.7874 -0.4064)
			(end 0.7874 -0.4064)
			(stroke
				(width 0.1524)
				(type default)
			)
			(layer "F.SilkS")
		)
		(fp_line
			(start -0.7874 0.4064)
			(end -0.7874 -0.4064)
			(stroke
				(width 0.1524)
				(type default)
			)
			(layer "F.SilkS")
		)
		(fp_line
			(start 0.7874 -0.4064)
			(end 0.7874 0.4064)
			(stroke
				(width 0.1524)
				(type default)
			)
			(layer "F.SilkS")
		)
		(fp_line
			(start 0.7874 0.4064)
			(end -0.7874 0.4064)
			(stroke
				(width 0.1524)
				(type default)
			)
			(layer "F.SilkS")
		)
		(fp_line
			(start -0.67945 -0.305054)
			(end -0.12065 -0.305054)
			(stroke
				(width 0.1)
				(type default)
			)
			(layer "F.Fab")
		)
		(fp_line
			(start -0.67945 0.3048)
			(end -0.67945 -0.305054)
			(stroke
				(width 0.1)
				(type default)
			)
			(layer "F.Fab")
		)
		(fp_line
			(start -0.12065 -0.305054)
			(end -0.12065 -0.2794)
			(stroke
				(width 0.1)
				(type default)
			)
			(layer "F.Fab")
		)
		(fp_line
			(start -0.12065 -0.2794)
			(end 0.12065 -0.2794)
			(stroke
				(width 0.1)
				(type default)
			)
			(layer "F.Fab")
		)
		(fp_line
			(start -0.12065 0.2794)
			(end -0.12065 0.3048)
			(stroke
				(width 0.1)
				(type default)
			)
			(layer "F.Fab")
		)
		(fp_line
			(start -0.12065 0.3048)
			(end -0.67945 0.3048)
			(stroke
				(width 0.1)
				(type default)
			)
			(layer "F.Fab")
		)
		(fp_line
			(start 0.120396 0.2794)
			(end -0.12065 0.2794)
			(stroke
				(width 0.1)
				(type default)
			)
			(layer "F.Fab")
		)
		(fp_line
			(start 0.120396 0.3048)
			(end 0.120396 0.2794)
			(stroke
				(width 0.1)
				(type default)
			)
			(layer "F.Fab")
		)
		(fp_line
			(start 0.12065 -0.3048)
			(end 0.67945 -0.3048)
			(stroke
				(width 0.1)
				(type default)
			)
			(layer "F.Fab")
		)
		(fp_line
			(start 0.12065 -0.2794)
			(end 0.12065 -0.3048)
			(stroke
				(width 0.1)
				(type default)
			)
			(layer "F.Fab")
		)
		(fp_line
			(start 0.67945 -0.3048)
			(end 0.67945 0.3048)
			(stroke
				(width 0.1)
				(type default)
			)
			(layer "F.Fab")
		)
		(fp_line
			(start 0.67945 0.3048)
			(end 0.120396 0.3048)
			(stroke
				(width 0.1)
				(type default)
			)
			(layer "F.Fab")
		)
		(pad "1" smd circle
			(at -0.40005 0)
			(size 0 0)
			(layers "F.Cu" "F.Mask" "F.Paste")
			(net "P12V_AUX")
		)
		(pad "2" smd circle
			(at 0.40005 0)
			(size 0 0)
			(layers "F.Cu" "F.Mask" "F.Paste")
			(net "FM_COMP_P3V3_AUX_VIN")
		)
	)
	(footprint ""
		(layer "F.Cu")
		(at 370.4082 -92.954348 90)
		(property "Reference" "R779"
			(at 0 0 90)
			(layer "F.SilkS")
			(hide yes)
			(effects
				(font
					(size 1.27 1.27)
				)
			)
		)
		(property "Value" ""
			(at 0 0 90)
			(layer "F.Fab")
			(effects
				(font
					(size 1.27 1.27)
				)
			)
		)
		(duplicate_pad_numbers_are_jumpers no)
		(fp_line
			(start 0.7874 -0.4064)
			(end 0.7874 0.4064)
			(stroke
				(width 0.1524)
				(type default)
			)
			(layer "F.SilkS")
		)
		(fp_line
			(start -0.7874 -0.4064)
			(end 0.7874 -0.4064)
			(stroke
				(width 0.1524)
				(type default)
			)
			(layer "F.SilkS")
		)
		(fp_line
			(start 0.7874 0.4064)
			(end -0.7874 0.4064)
			(stroke
				(width 0.1524)
				(type default)
			)
			(layer "F.SilkS")
		)
		(fp_line
			(start -0.7874 0.4064)
			(end -0.7874 -0.4064)
			(stroke
				(width 0.1524)
				(type default)
			)
			(layer "F.SilkS")
		)
		(fp_line
			(start -0.12065 -0.305054)
			(end -0.12065 -0.2794)
			(stroke
				(width 0.1)
				(type default)
			)
			(layer "F.Fab")
		)
		(fp_line
			(start -0.67945 -0.305054)
			(end -0.12065 -0.305054)
			(stroke
				(width 0.1)
				(type default)
			)
			(layer "F.Fab")
		)
		(fp_line
			(start 0.67945 -0.3048)
			(end 0.67945 0.3048)
			(stroke
				(width 0.1)
				(type default)
			)
			(layer "F.Fab")
		)
		(fp_line
			(start 0.12065 -0.3048)
			(end 0.67945 -0.3048)
			(stroke
				(width 0.1)
				(type default)
			)
			(layer "F.Fab")
		)
		(fp_line
			(start 0.12065 -0.2794)
			(end 0.12065 -0.3048)
			(stroke
				(width 0.1)
				(type default)
			)
			(layer "F.Fab")
		)
		(fp_line
			(start -0.12065 -0.2794)
			(end 0.12065 -0.2794)
			(stroke
				(width 0.1)
				(type default)
			)
			(layer "F.Fab")
		)
		(fp_line
			(start 0.120396 0.2794)
			(end -0.12065 0.2794)
			(stroke
				(width 0.1)
				(type default)
			)
			(layer "F.Fab")
		)
		(fp_line
			(start -0.12065 0.2794)
			(end -0.12065 0.3048)
			(stroke
				(width 0.1)
				(type default)
			)
			(layer "F.Fab")
		)
		(fp_line
			(start 0.67945 0.3048)
			(end 0.120396 0.3048)
			(stroke
				(width 0.1)
				(type default)
			)
			(layer "F.Fab")
		)
		(fp_line
			(start 0.120396 0.3048)
			(end 0.120396 0.2794)
			(stroke
				(width 0.1)
				(type default)
			)
			(layer "F.Fab")
		)
		(fp_line
			(start -0.12065 0.3048)
			(end -0.67945 0.3048)
			(stroke
				(width 0.1)
				(type default)
			)
			(layer "F.Fab")
		)
		(fp_line
			(start -0.67945 0.3048)
			(end -0.67945 -0.305054)
			(stroke
				(width 0.1)
				(type default)
			)
			(layer "F.Fab")
		)
		(pad "1" smd circle
			(at -0.40005 0 90)
			(size 0 0)
			(layers "F.Cu" "F.Mask" "F.Paste")
			(net "PVNN_TERM_CPU0")
		)
		(pad "2" smd circle
			(at 0.40005 0 90)
			(size 0 0)
			(layers "F.Cu" "F.Mask" "F.Paste")
			(net "FM_CPU_FBRK_DEBUG_N")
		)
	)
)
